# TIMECARD (Time Appliance Project (Time Card)) — schematic netlist excerpt (pin names and nets, part order shuffled) for the footprints in the layout excerpt that follows; sources: Cadence DE-HDL packaged netlist, KiCad conversion of R4006-B0001-02_R01.brd

C225  CAPACITOR  0.1UF 25V 10%  pkg SMC_0402R_H022  page 16 : \1\ = XP3R3V_FPGA ; \2\ = SG
SP42  NULL  pkg DUMMY  page 34
R351  RESISTOR  0OHM -  pkg SMC_0402R_H016  page 19 : \1\ = UNNAMED_8_ICP10100LGA10_I24_R_4 ; \2\ = SG

(kicad_pcb
	(version 20260206)
	(generator "pcbnew")
	(generator_version "10.0")
	(general
		(thickness 1.6)
		(legacy_teardrops no)
	)
	(paper "A4")
	(title_block
		(title "timecard-production-celestica-r4006 — R4006-B0001-02_R01.brd")
		(comment 1 "Time Appliance Project (Time Card) / footprints 584-587 of 1113")
	)
	(layers
		(0 "F.Cu" signal "TOP")
		(4 "In1.Cu" signal "L02_GND1")
		(6 "In2.Cu" signal "L03_SIG1")
		(8 "In3.Cu" signal "L04_GND2")
		(10 "In4.Cu" signal "L05_VCC1")
		(12 "In5.Cu" signal "L06_VCC2")
		(14 "In6.Cu" signal "L07_GND3")
		(16 "In7.Cu" signal "L08_SIG2")
		(18 "In8.Cu" signal "L09_GND4")
		(2 "B.Cu" signal "BOTTOM")
		(9 "F.Adhes" user "F.Adhesive")
		(11 "B.Adhes" user "B.Adhesive")
		(13 "F.Paste" user "Package Geometry/Pastemask Top")
		(15 "B.Paste" user "Package Geometry/Pastemask Bottom")
		(5 "F.SilkS" user "Ref Des/Silkscreen Top")
		(7 "B.SilkS" user "Ref Des/Silkscreen Bottom")
		(1 "F.Mask" user "Board Geometry/Soldermask Top")
		(3 "B.Mask" user "Board Geometry/Soldermask Bottom")
		(17 "Dwgs.User" user "User.Drawings")
		(19 "Cmts.User" user "User.Comments")
		(21 "Eco1.User" user "User.Eco1")
		(23 "Eco2.User" user "User.Eco2")
		(25 "Edge.Cuts" user "Board Geometry/Outline")
		(27 "Margin" user)
		(31 "F.CrtYd" user "Package Geometry/Place Bound Top")
		(29 "B.CrtYd" user "Package Geometry/Place Bound Bottom")
		(35 "F.Fab" user "Ref Des/Assembly Top")
		(33 "B.Fab" user "Ref Des/Assembly Bottom")
	)
	(footprint ""
		(layer "F.Cu")
		(at 21.209 -64.643 -90)
		(property "Reference" "R351"
			(at 1.27 -4.10337 90)
			(unlocked yes)
			(layer "F.SilkS")
			(effects
				(font
					(size 0.7874 0.5842)
					(thickness 0.1524)
				)
			)
		)
		(property "Value" "VAL*"
			(at 0.02032 2.13233 270)
			(unlocked yes)
			(layer "F.Fab")
			(hide yes)
			(effects
				(font
					(size 0.7874 0.5842)
					(thickness 0.1524)
				)
			)
		)
		(property "Tolerance" "TOL*"
			(at 0.044704 3.05435 270)
			(unlocked yes)
			(layer "Cmts.User")
			(hide yes)
			(effects
				(font
					(size 0.7874 0.5842)
					(thickness 0.1524)
				)
			)
		)
		(property "User Part Number" "PARTNUM*"
			(at 0.02032 4.024884 270)
			(unlocked yes)
			(layer "Cmts.User")
			(hide yes)
			(effects
				(font
					(size 0.7874 0.5842)
					(thickness 0.1524)
				)
			)
		)
		(property "Device Type" "RESISTOR-G155-100R0-J0,0OHM,-"
			(at 0.008382 1.210564 270)
			(unlocked yes)
			(layer "F.Fab")
			(hide yes)
			(effects
				(font
					(size 0.7874 0.5842)
					(thickness 0.1524)
				)
			)
		)
		(duplicate_pad_numbers_are_jumpers no)
		(fp_line
			(start -1.143 0.5588)
			(end 1.143 0.5588)
			(stroke
				(width 0.1)
				(type default)
			)
			(layer "F.SilkS")
		)
		(fp_line
			(start 1.143 0.5588)
			(end 1.143 -0.5588)
			(stroke
				(width 0.1)
				(type default)
			)
			(layer "F.SilkS")
		)
		(fp_line
			(start -1.143 -0.5588)
			(end -1.143 0.5588)
			(stroke
				(width 0.1)
				(type default)
			)
			(layer "F.SilkS")
		)
		(fp_line
			(start 1.143 -0.5588)
			(end -1.143 -0.5588)
			(stroke
				(width 0.1)
				(type default)
			)
			(layer "F.SilkS")
		)
		(fp_poly
			(pts
				(xy -1.143 0.5588) (xy 1.143 0.5588) (xy 1.143 -0.5588) (xy -1.143 -0.5588)
			)
			(stroke
				(width 0)
				(type default)
			)
			(fill no)
			(layer "F.CrtYd")
		)
		(fp_line
			(start -0.508 0.3048)
			(end 0.508 0.3048)
			(stroke
				(width 0.1)
				(type default)
			)
			(layer "F.Fab")
		)
		(fp_line
			(start 0.508 0.3048)
			(end 0.508 -0.3048)
			(stroke
				(width 0.1)
				(type default)
			)
			(layer "F.Fab")
		)
		(fp_line
			(start -0.508 -0.3048)
			(end -0.508 0.3048)
			(stroke
				(width 0.1)
				(type default)
			)
			(layer "F.Fab")
		)
		(fp_line
			(start 0.508 -0.3048)
			(end -0.508 -0.3048)
			(stroke
				(width 0.1)
				(type default)
			)
			(layer "F.Fab")
		)
		(pad "1" smd rect
			(at -0.5334 0 270)
			(size 0.7112 0.6096)
			(layers "F.Cu" "F.Mask" "F.Paste")
			(net "UNNAMED_8_ICP10100LGA10_I24_R_4")
		)
		(pad "2" smd rect
			(at 0.5334 0 270)
			(size 0.7112 0.6096)
			(layers "F.Cu" "F.Mask" "F.Paste")
			(net "SG")
		)
		(zone
			(layer "F.Cu")
			(hatch none 0.5)
			(connect_pads
				(clearance 0)
			)
			(min_thickness 0.25)
			(keepout
				(tracks allowed)
				(vias not_allowed)
				(pads allowed)
				(copperpour not_allowed)
				(footprints allowed)
			)
			(placement
				(enabled no)
				(sheetname "")
			)
			(fill
				(thermal_gap 0.5)
				(thermal_bridge_width 0.5)
				(island_removal_mode 0)
			)
			(polygon
				(pts
					(xy 20.9042 -64.7192) (xy 20.9042 -64.5668) (xy 21.5138 -64.5668) (xy 21.5138 -64.7192)
				)
			)
		)
		(zone
			(layer "F.Cu")
			(hatch none 0.5)
			(connect_pads
				(clearance 0)
			)
			(min_thickness 0.25)
			(keepout
				(tracks not_allowed)
				(vias allowed)
				(pads allowed)
				(copperpour not_allowed)
				(footprints allowed)
			)
			(placement
				(enabled no)
				(sheetname "")
			)
			(fill
				(thermal_gap 0.5)
				(thermal_bridge_width 0.5)
				(island_removal_mode 0)
			)
			(polygon
				(pts
					(xy 20.9042 -64.7192) (xy 20.9042 -64.5668) (xy 21.5138 -64.5668) (xy 21.5138 -64.7192)
				)
			)
		)
	)
	(footprint ""
		(layer "F.Cu")
		(at 30.34538 -15.58544)
		(property "Reference" "C225"
			(at -0.889 -5.29463 0)
			(unlocked yes)
			(layer "F.SilkS")
			(effects
				(font
					(size 0.7874 0.5842)
					(thickness 0.1524)
				)
			)
		)
		(property "Value" "VAL*"
			(at 0.0762 2.067306 0)
			(unlocked yes)
			(layer "F.Fab")
			(hide yes)
			(effects
				(font
					(size 0.7874 0.5842)
					(thickness 0.1524)
				)
			)
		)
		(property "Tolerance" "TOL*"
			(at 0.0762 3.032506 0)
			(unlocked yes)
			(layer "Cmts.User")
			(hide yes)
			(effects
				(font
					(size 0.7874 0.5842)
					(thickness 0.1524)
				)
			)
		)
		(property "User Part Number" "PARTNUM*"
			(at 0.1016 4.023106 0)
			(unlocked yes)
			(layer "Cmts.User")
			(hide yes)
			(effects
				(font
					(size 0.7874 0.5842)
					(thickness 0.1524)
				)
			)
		)
		(property "Device Type" "CAPACITOR-G105-0B104-EK,0.1UF,A"
			(at 0.0508 1.127506 0)
			(unlocked yes)
			(layer "F.Fab")
			(hide yes)
			(effects
				(font
					(size 0.7874 0.5842)
					(thickness 0.1524)
				)
			)
		)
		(duplicate_pad_numbers_are_jumpers no)
		(fp_line
			(start -1.143 -0.5588)
			(end -1.143 0.5588)
			(stroke
				(width 0.1)
				(type default)
			)
			(layer "F.SilkS")
		)
		(fp_line
			(start -1.143 0.5588)
			(end 1.143 0.5588)
			(stroke
				(width 0.1)
				(type default)
			)
			(layer "F.SilkS")
		)
		(fp_line
			(start 1.143 -0.5588)
			(end -1.143 -0.5588)
			(stroke
				(width 0.1)
				(type default)
			)
			(layer "F.SilkS")
		)
		(fp_line
			(start 1.143 0.5588)
			(end 1.143 -0.5588)
			(stroke
				(width 0.1)
				(type default)
			)
			(layer "F.SilkS")
		)
		(fp_rect
			(start -1.143 0.5588)
			(end 1.143 -0.5588)
			(stroke
				(width 0)
				(type default)
			)
			(fill no)
			(layer "F.CrtYd")
		)
		(fp_line
			(start -0.508 -0.3048)
			(end -0.508 0.3048)
			(stroke
				(width 0.1)
				(type default)
			)
			(layer "F.Fab")
		)
		(fp_line
			(start -0.508 0.3048)
			(end 0.508 0.3048)
			(stroke
				(width 0.1)
				(type default)
			)
			(layer "F.Fab")
		)
		(fp_line
			(start 0.508 -0.3048)
			(end -0.508 -0.3048)
			(stroke
				(width 0.1)
				(type default)
			)
			(layer "F.Fab")
		)
		(fp_line
			(start 0.508 0.3048)
			(end 0.508 -0.3048)
			(stroke
				(width 0.1)
				(type default)
			)
			(layer "F.Fab")
		)
		(pad "1" smd rect
			(at -0.5334 0)
			(size 0.7112 0.6096)
			(layers "F.Cu" "F.Mask" "F.Paste")
			(net "XP3R3V_FPGA")
		)
		(pad "2" smd rect
			(at 0.5334 0)
			(size 0.7112 0.6096)
			(layers "F.Cu" "F.Mask" "F.Paste")
			(net "SG")
		)
		(zone
			(layer "F.Cu")
			(hatch none 0.5)
			(connect_pads
				(clearance 0)
			)
			(min_thickness 0.25)
			(keepout
				(tracks allowed)
				(vias not_allowed)
				(pads allowed)
				(copperpour not_allowed)
				(footprints allowed)
			)
			(placement
				(enabled no)
				(sheetname "")
			)
			(fill
				(thermal_gap 0.5)
				(thermal_bridge_width 0.5)
				(island_removal_mode 0)
			)
			(polygon
				(pts
					(xy 30.26918 -15.28064) (xy 30.42158 -15.28064) (xy 30.42158 -15.89024) (xy 30.26918 -15.89024)
				)
			)
		)
	)
	(footprint ""
		(layer "F.Cu")
		(at 44.831 -128.016)
		(property "Reference" "SP42"
			(at 0 0 0)
			(layer "F.SilkS")
			(hide yes)
			(effects
				(font
					(size 1.27 1.27)
				)
			)
		)
		(property "Value" ""
			(at 0 0 0)
			(layer "F.Fab")
			(effects
				(font
					(size 1.27 1.27)
				)
			)
		)
		(duplicate_pad_numbers_are_jumpers no)
	)
	(footprint ""
		(layer "F.Cu")
		(at 38.608 -123.19)
		(property "Reference" "SP76"
			(at 0 0 0)
			(layer "F.SilkS")
			(hide yes)
			(effects
				(font
					(size 1.27 1.27)
				)
			)
		)
		(property "Value" ""
			(at 0 0 0)
			(layer "F.Fab")
			(effects
				(font
					(size 1.27 1.27)
				)
			)
		)
		(duplicate_pad_numbers_are_jumpers no)
	)
)
